FILE_TYPE = MACRO_DRAWING;
SET COLOR_WIRE YELLOW;
SET COLOR_PROP ORANGE;
SET COLOR_DOT WHITE;
SET COLOR_ARC YELLOW;
SET COLOR_BODY GREEN;
SET COLOR_NOTE PURPLE;
SET PROP_DISPLAY VALUE;
SET PAGE_NUMBER P230;
FORCEADD UNIVERSAL_POWER..1
(-1800 3350);
FORCEPROP 3 LASTPIN (-1800 3300) SIG_NAME P3V3_AUX\g
J 0
(-1790 3310);
DISPLAY 0.659574 (-1790 3310);
PAINT MONO (-1790 3310);
DISPLAY INVISIBLE (-1790 3310);
FORCEPROP 1 LAST HDL_POWER P3V3_AUX
J 1
(-1800 3400);
DISPLAY 0.872340 (-1800 3400);
PAINT GREEN (-1800 3400);
FORCEPROP 2 LAST CDS_LIB logical_power
J 0
(-1800 3350);
PAINT MONO (-1800 3350);
DISPLAY INVISIBLE (-1800 3350);
FORCEPROP 1 LAST PATH I10
J 0
(-1750 3375);
DISPLAY 0.872340 (-1750 3375);
PAINT AQUA (-1750 3375);
DISPLAY INVISIBLE (-1750 3375);
FORCEADD UNIVERSAL_GND..1
(-150 1850);
FORCEPROP 3 LASTPIN (-150 1900) SIG_NAME GND\g
J 0
(-140 1910);
DISPLAY 0.659574 (-140 1910);
PAINT MONO (-140 1910);
DISPLAY INVISIBLE (-140 1910);
FORCEPROP 1 LAST HDL_POWER GND
J 1
(-125 1775);
DISPLAY 0.872340 (-125 1775);
PAINT GREEN (-125 1775);
DISPLAY INVISIBLE (-125 1775);
FORCEPROP 1 LAST PATH I12
J 0
(-75 1850);
DISPLAY 0.872340 (-75 1850);
PAINT AQUA (-75 1850);
DISPLAY INVISIBLE (-75 1850);
FORCEPROP 2 LAST CDS_LIB logical_power
J 0
(-150 1850);
DISPLAY INVISIBLE (-150 1850);
FORCEADD UNIVERSAL_GND..1
(925 2250);
FORCEPROP 3 LASTPIN (925 2300) SIG_NAME GND\g
J 0
(935 2310);
DISPLAY 0.659574 (935 2310);
PAINT MONO (935 2310);
DISPLAY INVISIBLE (935 2310);
FORCEPROP 1 LAST PATH I13
J 0
(1000 2250);
DISPLAY 0.872340 (1000 2250);
PAINT AQUA (1000 2250);
DISPLAY INVISIBLE (1000 2250);
FORCEPROP 2 LAST CDS_LIB logical_power
J 0
(925 2250);
PAINT MONO (925 2250);
DISPLAY INVISIBLE (925 2250);
FORCEPROP 1 LAST HDL_POWER GND
J 1
(950 2175);
DISPLAY 0.872340 (950 2175);
PAINT GREEN (950 2175);
DISPLAY INVISIBLE (950 2175);
FORCEADD Q_CAP..1
(925 2475);
FORCEPROP 1 LAST PART_NUMBER CH4104K1B00
J 0
(975 2325);
DISPLAY 0.510638 (975 2325);
DISPLAY INVISIBLE (975 2325);
FORCEPROP 1 LAST TOLERANCE 10%
J 0
(975 2425);
DISPLAY 0.510638 (975 2425);
FORCEPROP 1 LAST VOLTAGE 25V
J 0
(975 2475);
DISPLAY 0.510638 (975 2475);
FORCEPROP 1 LAST MATERIAL X7R
J 0
(975 2375);
DISPLAY 0.510638 (975 2375);
FORCEPROP 1 LAST VALUE 0.1UF
J 0
(975 2525);
DISPLAY 0.510638 (975 2525);
FORCEPROP 1 LAST PACK_TYPE 0402
J 0
(975 2275);
DISPLAY 0.510638 (975 2275);
FORCEPROP 1 LAST $LOCATION C1775
J 0
(975 2575);
DISPLAY 0.787234 (975 2575);
FORCEPROP 1 LASTPIN (925 2575) $PN 1
J 0
(935 2555);
DISPLAY 0.787234 (935 2555);
FORCEPROP 1 LASTPIN (925 2375) $PN 2
J 0
(935 2355);
DISPLAY 0.787234 (935 2355);
FORCEPROP 1 LAST PATH I14
J 0
(975 2625);
DISPLAY 0.978723 (975 2625);
PAINT WHITE (975 2625);
DISPLAY INVISIBLE (975 2625);
FORCEPROP 2 LAST CDS_LIB pure_quanta
J 2
(925 2475);
PAINT MONO (925 2475);
DISPLAY INVISIBLE (925 2475);
FORCEPROP 2 LAST CDS_LOCATION C1775
J 0
(975 2675);
DISPLAY 1.021277 (975 2675);
DISPLAY INVISIBLE (975 2675);
FORCEPROP 2 LAST $SEC 1
J 0
(975 2675);
DISPLAY 0.680851 (975 2675);
PAINT MONO (975 2675);
DISPLAY INVISIBLE (975 2675);
FORCEPROP 2 LAST CDS_SEC 1
J 0
(975 2675);
DISPLAY 1.021277 (975 2675);
DISPLAY INVISIBLE (975 2675);
FORCEADD UNIVERSAL_POWER..1
(925 2800);
FORCEPROP 3 LASTPIN (925 2750) SIG_NAME P3V3_AUX\g
J 0
(935 2760);
DISPLAY 0.659574 (935 2760);
PAINT MONO (935 2760);
DISPLAY INVISIBLE (935 2760);
FORCEPROP 1 LAST HDL_POWER P3V3_AUX
J 1
(925 2850);
DISPLAY 0.872340 (925 2850);
PAINT GREEN (925 2850);
FORCEPROP 1 LAST PATH I15
J 0
(975 2825);
DISPLAY 0.872340 (975 2825);
PAINT AQUA (975 2825);
DISPLAY INVISIBLE (975 2825);
FORCEPROP 2 LAST CDS_LIB logical_power
J 0
(925 2800);
PAINT MONO (925 2800);
DISPLAY INVISIBLE (925 2800);
FORCEADD UNIVERSAL_GND..1
(1750 1550);
FORCEPROP 3 LASTPIN (1750 1600) SIG_NAME GND\g
J 0
(1760 1610);
DISPLAY 0.659574 (1760 1610);
PAINT MONO (1760 1610);
DISPLAY INVISIBLE (1760 1610);
FORCEPROP 1 LAST PATH I22
J 0
(1825 1550);
DISPLAY 0.872340 (1825 1550);
PAINT AQUA (1825 1550);
DISPLAY INVISIBLE (1825 1550);
FORCEPROP 2 LAST CDS_LIB logical_power
J 0
(1750 1550);
DISPLAY INVISIBLE (1750 1550);
FORCEPROP 1 LAST HDL_POWER GND
J 1
(1775 1475);
DISPLAY 0.872340 (1775 1475);
PAINT GREEN (1775 1475);
DISPLAY INVISIBLE (1775 1475);
FORCEADD Q_RES..1
(2000 2075);
FORCEPROP 1 LAST PART_NUMBER CS03322FB03
J 0
(1600 1975);
DISPLAY 0.723404 (1600 1975);
PAINT WHITE (1600 1975);
DISPLAY INVISIBLE (1600 1975);
FORCEPROP 1 LAST PACK_TYPE 0402LF
J 0
(1825 2025);
DISPLAY 0.723404 (1825 2025);
FORCEPROP 1 LAST MATERIAL CHIP
J 0
(2025 2025);
DISPLAY 0.723404 (2025 2025);
FORCEPROP 1 LAST VALUE 33.2
J 2
(2250 2075);
DISPLAY 0.723404 (2250 2075);
FORCEPROP 1 LAST $LOCATION R2944
J 0
(1800 2075);
DISPLAY 0.723404 (1800 2075);
FORCEPROP 1 LASTPIN (1900 2075) $PN 1
J 0
(1912 2087);
DISPLAY 0.723404 (1912 2087);
PAINT MONO (1912 2087);
FORCEPROP 1 LASTPIN (2100 2075) $PN 2
J 0
(2062 2087);
DISPLAY 0.723404 (2062 2087);
PAINT MONO (2062 2087);
FORCEPROP 1 LAST PATH I24
J 0
(1950 2225);
DISPLAY 0.978723 (1950 2225);
PAINT WHITE (1950 2225);
DISPLAY INVISIBLE (1950 2225);
FORCEPROP 2 LAST CDS_LIB pure_quanta
J 0
(2000 2075);
DISPLAY INVISIBLE (2000 2075);
FORCEPROP 1 LAST TOLERANCE 1%
J 0
(2475 2075);
DISPLAY 0.723404 (2475 2075);
PAINT SKYBLUE (2475 2075);
DISPLAY INVISIBLE (2475 2075);
FORCEPROP 1 LAST WATTAGE 1/16W
J 2
(2400 2025);
DISPLAY 0.723404 (2400 2025);
PAINT SKYBLUE (2400 2025);
DISPLAY INVISIBLE (2400 2025);
FORCEPROP 2 LAST CDS_LOCATION R2944
J 0
(1950 2275);
DISPLAY 1.021277 (1950 2275);
DISPLAY INVISIBLE (1950 2275);
FORCEPROP 2 LAST $SEC 1
J 0
(1950 2275);
DISPLAY 0.680851 (1950 2275);
PAINT MONO (1950 2275);
DISPLAY INVISIBLE (1950 2275);
FORCEPROP 0 LAST CDS_SEC 1
J 0
(1700 2150);
DISPLAY INVISIBLE (1700 2150);
FORCEADD Q_RES..2
(1725 2325);
FORCEPROP 1 LAST PART_NUMBER CS24702JB10
J 0
(1765 2150);
DISPLAY 0.638298 (1765 2150);
DISPLAY INVISIBLE (1765 2150);
FORCEPROP 1 LAST VALUE 4.7K
J 0
(1770 2400);
DISPLAY 0.638298 (1770 2400);
FORCEPROP 1 LAST TOLERANCE 5%
J 0
(1770 2350);
DISPLAY 0.638298 (1770 2350);
FORCEPROP 1 LAST WATTAGE 1/16W
J 0
(1765 2300);
DISPLAY 0.638298 (1765 2300);
FORCEPROP 1 LAST MATERIAL EMPTY
J 0
(1765 2250);
DISPLAY 0.638298 (1765 2250);
PAINT RED (1765 2250);
FORCEPROP 1 LAST PACK_TYPE 0402LF
J 0
(1765 2200);
DISPLAY 0.638298 (1765 2200);
FORCEPROP 1 LAST $LOCATION R2946
J 0
(1770 2450);
DISPLAY 0.638298 (1770 2450);
FORCEPROP 1 LASTPIN (1725 2425) $PN 1
J 0
(1730 2387);
DISPLAY 0.787234 (1730 2387);
FORCEPROP 1 LASTPIN (1725 2225) $PN 2
J 0
(1730 2235);
DISPLAY 0.787234 (1730 2235);
FORCEPROP 2 LAST CDS_LIB pure_quanta
J 0
(1725 2325);
PAINT MONO (1725 2325);
DISPLAY INVISIBLE (1725 2325);
FORCEPROP 1 LAST PATH I25
J 0
(1775 2500);
DISPLAY 0.978723 (1775 2500);
PAINT WHITE (1775 2500);
DISPLAY INVISIBLE (1775 2500);
FORCEPROP 2 LAST CDS_LOCATION R2946
J 0
(1775 2550);
DISPLAY 1.021277 (1775 2550);
DISPLAY INVISIBLE (1775 2550);
FORCEPROP 2 LAST $SEC 1
J 0
(1775 2550);
DISPLAY 0.680851 (1775 2550);
PAINT MONO (1775 2550);
DISPLAY INVISIBLE (1775 2550);
FORCEPROP 2 LAST CDS_SEC 1
J 0
(1775 2550);
DISPLAY 1.021277 (1775 2550);
DISPLAY INVISIBLE (1775 2550);
FORCEADD UNIVERSAL_POWER..1
(1725 2575);
FORCEPROP 3 LASTPIN (1725 2525) SIG_NAME P3V3_AUX\g
J 0
(1735 2535);
DISPLAY 0.659574 (1735 2535);
PAINT MONO (1735 2535);
DISPLAY INVISIBLE (1735 2535);
FORCEPROP 1 LAST HDL_POWER P3V3_AUX
J 1
(1725 2625);
DISPLAY 0.872340 (1725 2625);
PAINT GREEN (1725 2625);
FORCEPROP 2 LAST CDS_LIB logical_power
J 0
(1725 2575);
PAINT MONO (1725 2575);
DISPLAY INVISIBLE (1725 2575);
FORCEPROP 1 LAST PATH I26
J 0
(1775 2600);
DISPLAY 0.872340 (1775 2600);
PAINT AQUA (1775 2600);
DISPLAY INVISIBLE (1775 2600);
FORCEADD OFFPAGE..2
(3275 2075);
FORCEPROP 2 LAST $XR0 245 
J 0
(3464 2075);
DISPLAY 0.638298 (3464 2075);
PAINT MONO (3464 2075);
FORCEPROP 2 LAST PATH I27
J 0
(3475 2125);
DISPLAY 1.021277 (3475 2125);
DISPLAY INVISIBLE (3475 2125);
FORCEPROP 2 LAST CDS_LIB standard
J 0
(3275 2075);
DISPLAY INVISIBLE (3275 2075);
FORCEPROP 1 LAST OFFPAGE TRUE
J 0
(3600 1950);
DISPLAY 0.872340 (3600 1950);
PAINT AQUA (3600 1950);
DISPLAY INVISIBLE (3600 1950);
FORCEPROP 1 LAST COMMENT_BODY TRUE
J 0
(3230 1980);
DISPLAY 0.872340 (3230 1980);
PAINT GREEN (3230 1980);
DISPLAY INVISIBLE (3230 1980);
FORCEADD Q_RES..2
(-1800 3100);
FORCEPROP 1 LAST PART_NUMBER CS24702JB10
J 0
(-1760 2925);
DISPLAY 0.638298 (-1760 2925);
DISPLAY INVISIBLE (-1760 2925);
FORCEPROP 1 LAST VALUE 4.7K
J 0
(-1755 3175);
DISPLAY 0.638298 (-1755 3175);
FORCEPROP 1 LAST TOLERANCE 5%
J 0
(-1755 3125);
DISPLAY 0.638298 (-1755 3125);
FORCEPROP 1 LAST PACK_TYPE 0402LF
J 0
(-1760 2975);
DISPLAY 0.638298 (-1760 2975);
FORCEPROP 1 LAST MATERIAL EMPTY
J 0
(-1760 3025);
DISPLAY 0.638298 (-1760 3025);
PAINT RED (-1760 3025);
FORCEPROP 1 LAST WATTAGE 1/16W
J 0
(-1760 3075);
DISPLAY 0.638298 (-1760 3075);
FORCEPROP 1 LAST $LOCATION R2940
J 0
(-1755 3225);
DISPLAY 0.638298 (-1755 3225);
FORCEPROP 1 LASTPIN (-1800 3200) $PN 1
J 0
(-1795 3162);
DISPLAY 0.787234 (-1795 3162);
FORCEPROP 1 LASTPIN (-1800 3000) $PN 2
J 0
(-1795 3010);
DISPLAY 0.787234 (-1795 3010);
FORCEPROP 2 LAST CDS_LIB pure_quanta
J 0
(-1800 3100);
PAINT MONO (-1800 3100);
DISPLAY INVISIBLE (-1800 3100);
FORCEPROP 1 LAST PATH I28
J 0
(-1750 3275);
DISPLAY 0.978723 (-1750 3275);
PAINT WHITE (-1750 3275);
DISPLAY INVISIBLE (-1750 3275);
FORCEPROP 2 LAST CDS_LOCATION R2940
J 0
(-1750 3325);
DISPLAY 1.021277 (-1750 3325);
DISPLAY INVISIBLE (-1750 3325);
FORCEPROP 2 LAST $SEC 1
J 0
(-1750 3325);
DISPLAY 0.680851 (-1750 3325);
PAINT MONO (-1750 3325);
DISPLAY INVISIBLE (-1750 3325);
FORCEPROP 2 LAST CDS_SEC 1
J 0
(-1750 3325);
DISPLAY 1.021277 (-1750 3325);
DISPLAY INVISIBLE (-1750 3325);
FORCEADD Q_RES..2
(-1775 2625);
FORCEPROP 1 LAST PART_NUMBER CS41002FB09
J 0
(-1735 2500);
DISPLAY 0.510638 (-1735 2500);
DISPLAY INVISIBLE (-1735 2500);
FORCEPROP 1 LAST PACK_TYPE 0402LF
J 0
(-1735 2450);
DISPLAY 0.510638 (-1735 2450);
FORCEPROP 1 LAST TOLERANCE 1%
J 0
(-1730 2650);
DISPLAY 0.510638 (-1730 2650);
FORCEPROP 1 LAST WATTAGE 1/16W
J 0
(-1735 2600);
DISPLAY 0.510638 (-1735 2600);
FORCEPROP 1 LAST MATERIAL CHIP
J 0
(-1735 2550);
DISPLAY 0.510638 (-1735 2550);
FORCEPROP 1 LAST VALUE 100K
J 0
(-1730 2700);
DISPLAY 0.510638 (-1730 2700);
FORCEPROP 1 LAST $LOCATION R2941
J 0
(-1730 2750);
DISPLAY 0.978723 (-1730 2750);
FORCEPROP 1 LASTPIN (-1775 2725) $PN 1
J 0
(-1770 2687);
DISPLAY 0.787234 (-1770 2687);
PAINT MONO (-1770 2687);
FORCEPROP 1 LASTPIN (-1775 2525) $PN 2
J 0
(-1770 2535);
DISPLAY 0.787234 (-1770 2535);
PAINT MONO (-1770 2535);
FORCEPROP 2 LAST CDS_LIB pure_quanta
J 0
(-1775 2625);
DISPLAY INVISIBLE (-1775 2625);
FORCEPROP 1 LAST PATH I29
J 0
(-1725 2800);
DISPLAY 0.978723 (-1725 2800);
PAINT WHITE (-1725 2800);
DISPLAY INVISIBLE (-1725 2800);
FORCEPROP 0 LAST CDS_LOCATION R2941
J 0
(-1725 2800);
DISPLAY 1.021277 (-1725 2800);
DISPLAY INVISIBLE (-1725 2800);
FORCEPROP 0 LAST $SEC 1
J 0
(-1725 2800);
DISPLAY 0.680851 (-1725 2800);
PAINT MONO (-1725 2800);
DISPLAY INVISIBLE (-1725 2800);
FORCEPROP 0 LAST CDS_SEC 1
J 0
(-1725 2800);
DISPLAY 1.021277 (-1725 2800);
DISPLAY INVISIBLE (-1725 2800);
FORCEADD Q_RES..2
(1750 1775);
FORCEPROP 1 LAST PART_NUMBER CS24702JB10
J 0
(1790 1600);
DISPLAY 0.638298 (1790 1600);
DISPLAY INVISIBLE (1790 1600);
FORCEPROP 1 LAST WATTAGE 1/16W
J 0
(1790 1750);
DISPLAY 0.638298 (1790 1750);
FORCEPROP 1 LAST MATERIAL EMPTY
J 0
(1790 1700);
DISPLAY 0.638298 (1790 1700);
PAINT RED (1790 1700);
FORCEPROP 1 LAST TOLERANCE 5%
J 0
(1795 1800);
DISPLAY 0.638298 (1795 1800);
FORCEPROP 1 LAST PACK_TYPE 0402LF
J 0
(1790 1650);
DISPLAY 0.638298 (1790 1650);
FORCEPROP 1 LAST VALUE 4.7K
J 0
(1795 1850);
DISPLAY 0.638298 (1795 1850);
FORCEPROP 1 LAST $LOCATION R2948
J 0
(1795 1900);
DISPLAY 0.978723 (1795 1900);
FORCEPROP 1 LASTPIN (1750 1875) $PN 1
J 0
(1755 1837);
DISPLAY 0.787234 (1755 1837);
PAINT MONO (1755 1837);
FORCEPROP 1 LASTPIN (1750 1675) $PN 2
J 0
(1755 1685);
DISPLAY 0.787234 (1755 1685);
PAINT MONO (1755 1685);
FORCEPROP 1 LAST PATH I30
J 0
(1800 1950);
DISPLAY 0.978723 (1800 1950);
PAINT WHITE (1800 1950);
DISPLAY INVISIBLE (1800 1950);
FORCEPROP 2 LAST CDS_LIB pure_quanta
J 0
(1750 1775);
DISPLAY INVISIBLE (1750 1775);
FORCEPROP 0 LAST CDS_LOCATION R2948
J 0
(1800 1950);
DISPLAY 1.021277 (1800 1950);
DISPLAY INVISIBLE (1800 1950);
FORCEPROP 0 LAST $SEC 1
J 0
(1800 1950);
DISPLAY 0.680851 (1800 1950);
PAINT MONO (1800 1950);
DISPLAY INVISIBLE (1800 1950);
FORCEPROP 0 LAST CDS_SEC 1
J 0
(1800 1950);
DISPLAY 1.021277 (1800 1950);
DISPLAY INVISIBLE (1800 1950);
FORCEADD 74LVC1G08W57..1
(250 2125);
FORCEPROP 1 LAST PART_NUMBER AL1G0008020
J 0
(100 2350);
DISPLAY 0.723404 (100 2350);
PAINT GREEN (100 2350);
DISPLAY INVISIBLE (100 2350);
FORCEPROP 2 LAST PART_TYPE SMLF
J 0
(100 2450);
DISPLAY 0.808511 (100 2450);
FORCEPROP 2 LAST VALUE 74LVC1G08W5-7
J 0
(100 2400);
DISPLAY 0.808511 (100 2400);
FORCEPROP 1 LAST MATERIAL IC
J 0
(106 2282);
DISPLAY 0.723404 (106 2282);
PAINT GREEN (106 2282);
FORCEPROP 1 LAST $LOCATION U278
J 0
(106 2556);
DISPLAY 0.723404 (106 2556);
PAINT GREEN (106 2556);
FORCEPROP 0 LASTPIN (-50 2225) $PN 1
J 2
(-60 2235);
DISPLAY 0.680851 (-60 2235);
PAINT MONO (-60 2235);
FORCEPROP 0 LASTPIN (-50 2125) $PN 2
J 2
(-60 2135);
DISPLAY 0.680851 (-60 2135);
PAINT MONO (-60 2135);
FORCEPROP 0 LASTPIN (-50 2025) $PN 3
J 2
(-60 2035);
DISPLAY 0.680851 (-60 2035);
PAINT MONO (-60 2035);
FORCEPROP 0 LASTPIN (550 2225) $PN 5
J 0
(560 2235);
DISPLAY 0.680851 (560 2235);
PAINT MONO (560 2235);
FORCEPROP 0 LASTPIN (550 2075) $PN 4
J 0
(560 2085);
DISPLAY 0.680851 (560 2085);
PAINT MONO (560 2085);
FORCEPROP 2 LAST CDS_LIB pure_quanta
J 0
(250 2125);
DISPLAY INVISIBLE (250 2125);
FORCEPROP 1 LAST PATH I31
J 0
(250 2125);
DISPLAY 0.723404 (250 2125);
PAINT GREEN (250 2125);
DISPLAY INVISIBLE (250 2125);
FORCEPROP 1 LAST CDS_LMAN_SYM_OUTLINE -150,150,150,-150
J 0
(250 2125);
DISPLAY 0.468085 (250 2125);
PAINT GREEN (250 2125);
DISPLAY INVISIBLE (250 2125);
FORCEPROP 1 LAST NEEDS_NO_SIZE TRUE
J 0
(250 2125);
DISPLAY 0.723404 (250 2125);
PAINT GREEN (250 2125);
DISPLAY INVISIBLE (250 2125);
FORCEPROP 0 LAST CDS_LOCATION U278
J 0
(125 2600);
DISPLAY 1.021277 (125 2600);
DISPLAY INVISIBLE (125 2600);
FORCEPROP 0 LAST $SEC 1
J 0
(125 2600);
DISPLAY 0.680851 (125 2600);
PAINT MONO (125 2600);
DISPLAY INVISIBLE (125 2600);
FORCEPROP 0 LAST CDS_SEC 1
J 0
(125 2600);
DISPLAY 1.021277 (125 2600);
DISPLAY INVISIBLE (125 2600);
FORCEADD Q_RES..1
(-1325 2125);
FORCEPROP 1 LAST PART_NUMBER CS00002JB13
J 0
(-1200 2150);
DISPLAY 0.319149 (-1200 2150);
DISPLAY INVISIBLE (-1200 2150);
FORCEPROP 1 LAST WATTAGE 1/16W
J 2
(-1025 2175);
DISPLAY 0.319149 (-1025 2175);
FORCEPROP 1 LAST MATERIAL CHIP
J 0
(-1075 2125);
DISPLAY 0.404255 (-1075 2125);
FORCEPROP 1 LAST TOLERANCE 5%
J 0
(-1150 2125);
DISPLAY 0.404255 (-1150 2125);
FORCEPROP 1 LAST VALUE 0
J 2
(-1175 2125);
DISPLAY 0.404255 (-1175 2125);
FORCEPROP 1 LAST PACK_TYPE 0402LF
J 0
(-1200 2175);
DISPLAY 0.319149 (-1200 2175);
FORCEPROP 1 LAST $LOCATION R3770
J 0
(-1550 2125);
DISPLAY 0.638298 (-1550 2125);
FORCEPROP 1 LASTPIN (-1425 2125) $PN 1
J 0
(-1413 2137);
DISPLAY 0.787234 (-1413 2137);
PAINT MONO (-1413 2137);
FORCEPROP 1 LASTPIN (-1225 2125) $PN 2
J 0
(-1263 2137);
DISPLAY 0.787234 (-1263 2137);
PAINT MONO (-1263 2137);
FORCEPROP 2 LAST CDS_LIB pure_quanta
J 0
(-1325 2125);
DISPLAY INVISIBLE (-1325 2125);
FORCEPROP 1 LAST PATH I34
J 0
(-1375 2275);
DISPLAY 0.978723 (-1375 2275);
PAINT WHITE (-1375 2275);
DISPLAY INVISIBLE (-1375 2275);
FORCEPROP 0 LAST CDS_LOCATION R3770
J 0
(-1025 2200);
DISPLAY 1.021277 (-1025 2200);
DISPLAY INVISIBLE (-1025 2200);
FORCEPROP 0 LAST $SEC 1
J 0
(-1025 2200);
DISPLAY 0.680851 (-1025 2200);
PAINT MONO (-1025 2200);
DISPLAY INVISIBLE (-1025 2200);
FORCEPROP 0 LAST CDS_SEC 1
J 0
(-1025 2200);
DISPLAY 1.021277 (-1025 2200);
DISPLAY INVISIBLE (-1025 2200);
FORCEADD OFFPAGE..4
R 2
(-2025 2125);
FORCEPROP 2 LAST $XR0 147 
J 0
(-2277 2125);
DISPLAY 0.638298 (-2277 2125);
PAINT MONO (-2277 2125);
FORCEPROP 2 LAST CDS_LIB standard
J 0
(-2025 2125);
DISPLAY INVISIBLE (-2025 2125);
FORCEPROP 2 LAST PATH I35
J 0
(-1975 2200);
DISPLAY 1.021277 (-1975 2200);
DISPLAY INVISIBLE (-1975 2200);
FORCEPROP 1 LAST COMMENT_BODY TRUE
J 2
(-2000 2025);
DISPLAY 0.872340 (-2000 2025);
PAINT GREEN (-2000 2025);
DISPLAY INVISIBLE (-2000 2025);
FORCEPROP 1 LAST OFFPAGE TRUE
J 2
(-2350 2000);
DISPLAY 0.872340 (-2350 2000);
PAINT GREEN (-2350 2000);
DISPLAY INVISIBLE (-2350 2000);
FORCEADD UNIVERSAL_GND..1
(-25 75);
FORCEPROP 3 LASTPIN (-25 125) SIG_NAME GND\g
J 0
(-15 135);
DISPLAY 0.659574 (-15 135);
PAINT MONO (-15 135);
DISPLAY INVISIBLE (-15 135);
FORCEPROP 2 LAST CDS_LIB logical_power
J 0
(-25 75);
DISPLAY INVISIBLE (-25 75);
FORCEPROP 1 LAST HDL_POWER GND
J 1
(0 0);
DISPLAY 0.872340 (0 0);
PAINT GREEN (0 0);
DISPLAY INVISIBLE (0 0);
FORCEPROP 1 LAST PATH I36
J 0
(50 75);
DISPLAY 0.872340 (50 75);
PAINT AQUA (50 75);
DISPLAY INVISIBLE (50 75);
FORCEADD 74LVC2G07DW7..1
(550 225);
FORCEPROP 1 LAST PART_NUMBER AL002G07003
J 0
(381 459);
DISPLAY 0.723404 (381 459);
PAINT GREEN (381 459);
DISPLAY INVISIBLE (381 459);
FORCEPROP 1 LAST MATERIAL IC
J 0
(381 332);
DISPLAY 0.723404 (381 332);
PAINT GREEN (381 332);
FORCEPROP 2 LAST PART_TYPE SMLF
J 0
(400 700);
DISPLAY 1.021277 (400 700);
FORCEPROP 2 LAST VALUE 74LVC2G07DW-7
J 0
(250 525);
DISPLAY 1.021277 (250 525);
FORCEPROP 1 LAST $LOCATION U308
J 0
(381 606);
DISPLAY 0.723404 (381 606);
PAINT GREEN (381 606);
FORCEPROP 0 LASTPIN (225 275) $PN 1
J 2
(215 285);
DISPLAY 0.680851 (215 285);
PAINT MONO (215 285);
FORCEPROP 0 LASTPIN (875 275) $PN 6
J 0
(885 285);
DISPLAY 0.680851 (885 285);
PAINT MONO (885 285);
FORCEPROP 0 LASTPIN (225 175) $PN 3
J 2
(215 185);
DISPLAY 0.680851 (215 185);
PAINT MONO (215 185);
FORCEPROP 0 LASTPIN (875 175) $PN 4
J 0
(885 185);
DISPLAY 0.680851 (885 185);
PAINT MONO (885 185);
FORCEPROP 0 LASTPIN (225 225) $PN 2
J 2
(215 235);
DISPLAY 0.680851 (215 235);
PAINT MONO (215 235);
FORCEPROP 0 LASTPIN (875 225) $PN 5
J 0
(885 235);
DISPLAY 0.680851 (885 235);
PAINT MONO (885 235);
FORCEPROP 2 LAST CDS_LIB pure_quanta
J 0
(550 225);
DISPLAY INVISIBLE (550 225);
FORCEPROP 1 LAST NEEDS_NO_SIZE TRUE
J 0
(550 225);
DISPLAY 0.723404 (550 225);
PAINT GREEN (550 225);
DISPLAY INVISIBLE (550 225);
FORCEPROP 1 LAST CDS_LMAN_SYM_OUTLINE -175,100,175,-100
J 0
(550 225);
DISPLAY 0.468085 (550 225);
PAINT GREEN (550 225);
DISPLAY INVISIBLE (550 225);
FORCEPROP 1 LAST PATH I37
J 0
(550 225);
DISPLAY 0.723404 (550 225);
PAINT GREEN (550 225);
DISPLAY INVISIBLE (550 225);
FORCEPROP 0 LAST CDS_LOCATION U308
J 0
(400 750);
DISPLAY 1.021277 (400 750);
DISPLAY INVISIBLE (400 750);
FORCEPROP 0 LAST $SEC 1
J 0
(400 750);
DISPLAY 0.680851 (400 750);
PAINT MONO (400 750);
DISPLAY INVISIBLE (400 750);
FORCEPROP 0 LAST CDS_SEC 1
J 0
(400 750);
DISPLAY 1.021277 (400 750);
DISPLAY INVISIBLE (400 750);
FORCEADD UNIVERSAL_POWER..1
(1250 -25);
FORCEPROP 3 LASTPIN (1250 -75) SIG_NAME P3V3_AUX\g
J 0
(1260 -65);
DISPLAY 0.659574 (1260 -65);
PAINT MONO (1260 -65);
DISPLAY INVISIBLE (1260 -65);
FORCEPROP 1 LAST HDL_POWER P3V3_AUX
J 1
(1250 25);
DISPLAY 0.872340 (1250 25);
PAINT GREEN (1250 25);
FORCEPROP 1 LAST PATH I38
J 0
(1300 0);
DISPLAY 0.872340 (1300 0);
PAINT AQUA (1300 0);
DISPLAY INVISIBLE (1300 0);
FORCEPROP 2 LAST CDS_LIB logical_power
J 0
(1250 -25);
PAINT MONO (1250 -25);
DISPLAY INVISIBLE (1250 -25);
FORCEADD UNIVERSAL_GND..1
(1250 -575);
FORCEPROP 3 LASTPIN (1250 -525) SIG_NAME GND\g
J 0
(1260 -515);
DISPLAY 0.659574 (1260 -515);
PAINT MONO (1260 -515);
DISPLAY INVISIBLE (1260 -515);
FORCEPROP 1 LAST PATH I39
J 0
(1325 -575);
DISPLAY 0.872340 (1325 -575);
PAINT AQUA (1325 -575);
DISPLAY INVISIBLE (1325 -575);
FORCEPROP 2 LAST CDS_LIB logical_power
J 0
(1250 -575);
PAINT MONO (1250 -575);
DISPLAY INVISIBLE (1250 -575);
FORCEPROP 1 LAST HDL_POWER GND
J 1
(1275 -650);
DISPLAY 0.872340 (1275 -650);
PAINT GREEN (1275 -650);
DISPLAY INVISIBLE (1275 -650);
FORCEADD Q_CAP..1
(1250 -350);
FORCEPROP 1 LAST PART_NUMBER CH4104K1B00
J 0
(1300 -500);
DISPLAY 0.510638 (1300 -500);
DISPLAY INVISIBLE (1300 -500);
FORCEPROP 1 LAST VALUE 0.1UF
J 0
(1300 -300);
DISPLAY 0.510638 (1300 -300);
FORCEPROP 1 LAST PACK_TYPE 0402
J 0
(1300 -550);
DISPLAY 0.510638 (1300 -550);
FORCEPROP 1 LAST VOLTAGE 25V
J 0
(1300 -350);
DISPLAY 0.510638 (1300 -350);
FORCEPROP 1 LAST TOLERANCE 10%
J 0
(1300 -400);
DISPLAY 0.510638 (1300 -400);
FORCEPROP 1 LAST MATERIAL X7R
J 0
(1300 -450);
DISPLAY 0.510638 (1300 -450);
FORCEPROP 1 LAST $LOCATION C2283
J 0
(1300 -250);
DISPLAY 0.787234 (1300 -250);
FORCEPROP 1 LASTPIN (1250 -250) $PN 1
J 0
(1260 -270);
DISPLAY 0.787234 (1260 -270);
FORCEPROP 1 LASTPIN (1250 -450) $PN 2
J 0
(1260 -470);
DISPLAY 0.787234 (1260 -470);
FORCEPROP 1 LAST PATH I40
J 0
(1300 -200);
DISPLAY 0.978723 (1300 -200);
PAINT WHITE (1300 -200);
DISPLAY INVISIBLE (1300 -200);
FORCEPROP 2 LAST CDS_LIB pure_quanta
J 2
(1250 -350);
PAINT MONO (1250 -350);
DISPLAY INVISIBLE (1250 -350);
FORCEPROP 2 LAST CDS_LOCATION C2283
J 0
(1300 -150);
DISPLAY 1.021277 (1300 -150);
DISPLAY INVISIBLE (1300 -150);
FORCEPROP 2 LAST $SEC 1
J 0
(1300 -150);
DISPLAY 0.680851 (1300 -150);
PAINT MONO (1300 -150);
DISPLAY INVISIBLE (1300 -150);
FORCEPROP 2 LAST CDS_SEC 1
J 0
(1300 -150);
DISPLAY 1.021277 (1300 -150);
DISPLAY INVISIBLE (1300 -150);
FORCEADD Q_RES..1
(-1125 275);
FORCEPROP 1 LAST PART_NUMBER CS00002JB13
J 0
(-1000 300);
DISPLAY 0.319149 (-1000 300);
DISPLAY INVISIBLE (-1000 300);
FORCEPROP 1 LAST VALUE 0
J 2
(-975 275);
DISPLAY 0.404255 (-975 275);
FORCEPROP 1 LAST PACK_TYPE 0402LF
J 0
(-1000 325);
DISPLAY 0.319149 (-1000 325);
FORCEPROP 1 LAST WATTAGE 1/16W
J 2
(-825 325);
DISPLAY 0.319149 (-825 325);
FORCEPROP 1 LAST MATERIAL CHIP
J 0
(-875 275);
DISPLAY 0.404255 (-875 275);
FORCEPROP 1 LAST TOLERANCE 5%
J 0
(-950 275);
DISPLAY 0.404255 (-950 275);
FORCEPROP 1 LAST $LOCATION R4268
J 0
(-1175 325);
DISPLAY 0.978723 (-1175 325);
FORCEPROP 1 LASTPIN (-1225 275) $PN 1
J 0
(-1213 287);
DISPLAY 0.787234 (-1213 287);
PAINT MONO (-1213 287);
FORCEPROP 1 LASTPIN (-1025 275) $PN 2
J 0
(-1063 287);
DISPLAY 0.787234 (-1063 287);
PAINT MONO (-1063 287);
FORCEPROP 1 LAST PATH I41
J 0
(-1175 425);
DISPLAY 0.978723 (-1175 425);
PAINT WHITE (-1175 425);
DISPLAY INVISIBLE (-1175 425);
FORCEPROP 2 LAST CDS_LIB pure_quanta
J 0
(-1125 275);
DISPLAY INVISIBLE (-1125 275);
FORCEPROP 0 LAST CDS_LOCATION R4268
J 0
(-1175 375);
DISPLAY 1.021277 (-1175 375);
DISPLAY INVISIBLE (-1175 375);
FORCEPROP 0 LAST $SEC 1
J 0
(-1175 375);
DISPLAY 0.680851 (-1175 375);
PAINT MONO (-1175 375);
DISPLAY INVISIBLE (-1175 375);
FORCEPROP 0 LAST CDS_SEC 1
J 0
(-1175 375);
DISPLAY 1.021277 (-1175 375);
DISPLAY INVISIBLE (-1175 375);
FORCEADD OFFPAGE..4
R 2
(-2175 275);
FORCEPROP 2 LAST $XR0 222 
J 0
(-2457 275);
DISPLAY 0.638298 (-2457 275);
PAINT MONO (-2457 275);
FORCEPROP 2 LAST CDS_LIB standard
J 0
(-2175 275);
DISPLAY INVISIBLE (-2175 275);
FORCEPROP 2 LAST PATH I42
J 0
(-2125 350);
DISPLAY 1.021277 (-2125 350);
DISPLAY INVISIBLE (-2125 350);
FORCEPROP 1 LAST OFFPAGE TRUE
J 2
(-2500 150);
DISPLAY 0.872340 (-2500 150);
PAINT GREEN (-2500 150);
DISPLAY INVISIBLE (-2500 150);
FORCEPROP 1 LAST COMMENT_BODY TRUE
J 2
(-2150 175);
DISPLAY 0.872340 (-2150 175);
PAINT GREEN (-2150 175);
DISPLAY INVISIBLE (-2150 175);
FORCEADD Q_RES..2
(2175 -25);
FORCEPROP 1 LAST PART_NUMBER CS24702JB10
J 0
(2215 -200);
DISPLAY 0.638298 (2215 -200);
DISPLAY INVISIBLE (2215 -200);
FORCEPROP 1 LAST VALUE 4.7K
J 0
(2220 50);
DISPLAY 0.638298 (2220 50);
FORCEPROP 1 LAST TOLERANCE 5%
J 0
(2220 0);
DISPLAY 0.638298 (2220 0);
FORCEPROP 1 LAST MATERIAL EMPTY
J 0
(2215 -100);
DISPLAY 0.638298 (2215 -100);
PAINT RED (2215 -100);
FORCEPROP 1 LAST WATTAGE 1/16W
J 0
(2215 -50);
DISPLAY 0.638298 (2215 -50);
FORCEPROP 1 LAST PACK_TYPE 0402LF
J 0
(2215 -150);
DISPLAY 0.638298 (2215 -150);
FORCEPROP 1 LAST $LOCATION R4265
J 0
(2220 100);
DISPLAY 0.978723 (2220 100);
FORCEPROP 1 LASTPIN (2175 75) $PN 1
J 0
(2180 37);
DISPLAY 0.787234 (2180 37);
PAINT MONO (2180 37);
FORCEPROP 1 LASTPIN (2175 -125) $PN 2
J 0
(2180 -115);
DISPLAY 0.787234 (2180 -115);
PAINT MONO (2180 -115);
FORCEPROP 1 LAST PATH I43
J 0
(2225 150);
DISPLAY 0.978723 (2225 150);
PAINT WHITE (2225 150);
DISPLAY INVISIBLE (2225 150);
FORCEPROP 2 LAST CDS_LIB pure_quanta
J 0
(2175 -25);
DISPLAY INVISIBLE (2175 -25);
FORCEPROP 0 LAST CDS_LOCATION R4265
J 0
(2225 150);
DISPLAY 1.021277 (2225 150);
DISPLAY INVISIBLE (2225 150);
FORCEPROP 0 LAST $SEC 1
J 0
(2225 150);
DISPLAY 0.680851 (2225 150);
PAINT MONO (2225 150);
DISPLAY INVISIBLE (2225 150);
FORCEPROP 0 LAST CDS_SEC 1
J 0
(2225 150);
DISPLAY 1.021277 (2225 150);
DISPLAY INVISIBLE (2225 150);
FORCEADD UNIVERSAL_GND..1
(2175 -250);
FORCEPROP 3 LASTPIN (2175 -200) SIG_NAME GND\g
J 0
(2185 -190);
DISPLAY 0.659574 (2185 -190);
PAINT MONO (2185 -190);
DISPLAY INVISIBLE (2185 -190);
FORCEPROP 1 LAST PATH I44
J 0
(2250 -250);
DISPLAY 0.872340 (2250 -250);
PAINT AQUA (2250 -250);
DISPLAY INVISIBLE (2250 -250);
FORCEPROP 1 LAST HDL_POWER GND
J 1
(2200 -325);
DISPLAY 0.872340 (2200 -325);
PAINT GREEN (2200 -325);
DISPLAY INVISIBLE (2200 -325);
FORCEPROP 2 LAST CDS_LIB logical_power
J 0
(2175 -250);
DISPLAY INVISIBLE (2175 -250);
FORCEADD OFFPAGE..2
(3675 275);
FORCEPROP 2 LAST $XR0 245 
J 0
(3864 275);
DISPLAY 0.638298 (3864 275);
PAINT MONO (3864 275);
FORCEPROP 2 LAST CDS_LIB standard
J 0
(3675 275);
DISPLAY INVISIBLE (3675 275);
FORCEPROP 1 LAST OFFPAGE TRUE
J 0
(4000 150);
DISPLAY 0.872340 (4000 150);
PAINT AQUA (4000 150);
DISPLAY INVISIBLE (4000 150);
FORCEPROP 1 LAST COMMENT_BODY TRUE
J 0
(3630 180);
DISPLAY 0.872340 (3630 180);
PAINT GREEN (3630 180);
DISPLAY INVISIBLE (3630 180);
FORCEPROP 2 LAST PATH I45
J 0
(3875 325);
DISPLAY 1.021277 (3875 325);
DISPLAY INVISIBLE (3875 325);
FORCEADD UNIVERSAL_POWER..1
(2150 775);
FORCEPROP 3 LASTPIN (2150 725) SIG_NAME P3V3_AUX\g
J 0
(2160 735);
DISPLAY 0.659574 (2160 735);
PAINT MONO (2160 735);
DISPLAY INVISIBLE (2160 735);
FORCEPROP 1 LAST HDL_POWER P3V3_AUX
J 1
(2150 825);
DISPLAY 0.872340 (2150 825);
PAINT GREEN (2150 825);
FORCEPROP 2 LAST CDS_LIB logical_power
J 0
(2150 775);
PAINT MONO (2150 775);
DISPLAY INVISIBLE (2150 775);
FORCEPROP 1 LAST PATH I46
J 0
(2200 800);
DISPLAY 0.872340 (2200 800);
PAINT AQUA (2200 800);
DISPLAY INVISIBLE (2200 800);
FORCEADD Q_RES..2
(2150 525);
FORCEPROP 1 LAST PART_NUMBER CS24702JB10
J 0
(2190 350);
DISPLAY 0.638298 (2190 350);
DISPLAY INVISIBLE (2190 350);
FORCEPROP 1 LAST VALUE 4.7K
J 0
(2195 600);
DISPLAY 0.638298 (2195 600);
FORCEPROP 1 LAST TOLERANCE 5%
J 0
(2195 550);
DISPLAY 0.638298 (2195 550);
FORCEPROP 1 LAST PACK_TYPE 0402LF
J 0
(2190 400);
DISPLAY 0.638298 (2190 400);
FORCEPROP 1 LAST WATTAGE 1/16W
J 0
(2190 500);
DISPLAY 0.638298 (2190 500);
FORCEPROP 1 LAST MATERIAL CHIP
J 0
(2190 450);
DISPLAY 0.638298 (2190 450);
FORCEPROP 1 LAST $LOCATION R4264
J 0
(2195 650);
DISPLAY 0.638298 (2195 650);
FORCEPROP 1 LASTPIN (2150 625) $PN 1
J 0
(2155 587);
DISPLAY 0.787234 (2155 587);
FORCEPROP 1 LASTPIN (2150 425) $PN 2
J 0
(2155 435);
DISPLAY 0.787234 (2155 435);
FORCEPROP 1 LAST PATH I47
J 0
(2200 700);
DISPLAY 0.978723 (2200 700);
PAINT WHITE (2200 700);
DISPLAY INVISIBLE (2200 700);
FORCEPROP 2 LAST CDS_LIB pure_quanta
J 0
(2150 525);
PAINT MONO (2150 525);
DISPLAY INVISIBLE (2150 525);
FORCEPROP 2 LAST CDS_LOCATION R4264
J 0
(2200 750);
DISPLAY 1.021277 (2200 750);
DISPLAY INVISIBLE (2200 750);
FORCEPROP 2 LAST $SEC 1
J 0
(2200 750);
DISPLAY 0.680851 (2200 750);
PAINT MONO (2200 750);
DISPLAY INVISIBLE (2200 750);
FORCEPROP 2 LAST CDS_SEC 1
J 0
(2200 750);
DISPLAY 1.021277 (2200 750);
DISPLAY INVISIBLE (2200 750);
FORCEADD Q_RES..1
(2400 275);
FORCEPROP 1 LAST PART_NUMBER CS03322FB03
J 0
(2000 175);
DISPLAY 0.723404 (2000 175);
PAINT WHITE (2000 175);
DISPLAY INVISIBLE (2000 175);
FORCEPROP 1 LAST MATERIAL CHIP
J 0
(2425 225);
DISPLAY 0.723404 (2425 225);
FORCEPROP 1 LAST PACK_TYPE 0402LF
J 0
(2225 225);
DISPLAY 0.723404 (2225 225);
FORCEPROP 1 LAST VALUE 33.2
J 2
(2650 275);
DISPLAY 0.723404 (2650 275);
FORCEPROP 1 LAST $LOCATION R4266
J 0
(2200 275);
DISPLAY 0.723404 (2200 275);
FORCEPROP 1 LASTPIN (2300 275) $PN 1
J 0
(2312 287);
DISPLAY 0.723404 (2312 287);
PAINT MONO (2312 287);
FORCEPROP 1 LASTPIN (2500 275) $PN 2
J 0
(2462 287);
DISPLAY 0.723404 (2462 287);
PAINT MONO (2462 287);
FORCEPROP 2 LAST CDS_LIB pure_quanta
J 0
(2400 275);
DISPLAY INVISIBLE (2400 275);
FORCEPROP 1 LAST TOLERANCE 1%
J 0
(2875 275);
DISPLAY 0.723404 (2875 275);
PAINT SKYBLUE (2875 275);
DISPLAY INVISIBLE (2875 275);
FORCEPROP 1 LAST WATTAGE 1/16W
J 2
(2800 225);
DISPLAY 0.723404 (2800 225);
PAINT SKYBLUE (2800 225);
DISPLAY INVISIBLE (2800 225);
FORCEPROP 1 LAST PATH I48
J 0
(2350 425);
DISPLAY 0.978723 (2350 425);
PAINT WHITE (2350 425);
DISPLAY INVISIBLE (2350 425);
FORCEPROP 2 LAST CDS_LOCATION R4266
J 0
(2350 475);
DISPLAY 1.021277 (2350 475);
DISPLAY INVISIBLE (2350 475);
FORCEPROP 2 LAST $SEC 1
J 0
(2350 475);
DISPLAY 0.680851 (2350 475);
PAINT MONO (2350 475);
DISPLAY INVISIBLE (2350 475);
FORCEPROP 0 LAST CDS_SEC 1
J 0
(2100 350);
DISPLAY INVISIBLE (2100 350);
FORCEADD OFFPAGE..4
R 2
(-1375 -2075);
FORCEPROP 2 LAST $XR0 245 
J 0
(-1657 -2075);
DISPLAY 0.638298 (-1657 -2075);
PAINT MONO (-1657 -2075);
FORCEPROP 2 LAST PATH I49
J 0
(-1625 -2025);
DISPLAY 1.021277 (-1625 -2025);
DISPLAY INVISIBLE (-1625 -2025);
FORCEPROP 1 LAST OFFPAGE TRUE
J 2
(-1700 -2200);
DISPLAY 0.872340 (-1700 -2200);
PAINT GREEN (-1700 -2200);
DISPLAY INVISIBLE (-1700 -2200);
FORCEPROP 1 LAST COMMENT_BODY TRUE
J 2
(-1350 -2175);
DISPLAY 0.872340 (-1350 -2175);
PAINT GREEN (-1350 -2175);
DISPLAY INVISIBLE (-1350 -2175);
FORCEPROP 2 LAST CDS_LIB standard
J 0
(-1375 -2075);
DISPLAY INVISIBLE (-1375 -2075);
FORCEADD Q_RES..2
(-1100 -2275);
FORCEPROP 1 LAST PART_NUMBER CS41002FB09
J 0
(-1060 -2400);
DISPLAY 0.510638 (-1060 -2400);
DISPLAY INVISIBLE (-1060 -2400);
FORCEPROP 1 LAST MATERIAL CHIP
J 0
(-1060 -2350);
DISPLAY 0.510638 (-1060 -2350);
FORCEPROP 1 LAST WATTAGE 1/16W
J 0
(-1060 -2300);
DISPLAY 0.510638 (-1060 -2300);
FORCEPROP 1 LAST TOLERANCE 1%
J 0
(-1055 -2250);
DISPLAY 0.510638 (-1055 -2250);
FORCEPROP 1 LAST VALUE 100K
J 0
(-1055 -2200);
DISPLAY 0.510638 (-1055 -2200);
FORCEPROP 1 LAST PACK_TYPE 0402LF
J 0
(-1060 -2450);
DISPLAY 0.510638 (-1060 -2450);
FORCEPROP 1 LAST $LOCATION R4552
J 0
(-1055 -2150);
DISPLAY 0.978723 (-1055 -2150);
FORCEPROP 1 LASTPIN (-1100 -2175) $PN 1
J 0
(-1095 -2213);
DISPLAY 0.787234 (-1095 -2213);
PAINT MONO (-1095 -2213);
FORCEPROP 1 LASTPIN (-1100 -2375) $PN 2
J 0
(-1095 -2365);
DISPLAY 0.787234 (-1095 -2365);
PAINT MONO (-1095 -2365);
FORCEPROP 2 LAST CDS_LIB pure_quanta
J 0
(-1100 -2275);
DISPLAY INVISIBLE (-1100 -2275);
FORCEPROP 1 LAST PATH I50
J 0
(-1050 -2100);
DISPLAY 0.978723 (-1050 -2100);
PAINT WHITE (-1050 -2100);
DISPLAY INVISIBLE (-1050 -2100);
FORCEPROP 0 LAST CDS_LOCATION R4552
J 0
(-1050 -2100);
DISPLAY 1.021277 (-1050 -2100);
DISPLAY INVISIBLE (-1050 -2100);
FORCEPROP 0 LAST $SEC 1
J 0
(-1050 -2100);
DISPLAY 0.680851 (-1050 -2100);
PAINT MONO (-1050 -2100);
DISPLAY INVISIBLE (-1050 -2100);
FORCEPROP 0 LAST CDS_SEC 1
J 0
(-1050 -2100);
DISPLAY 1.021277 (-1050 -2100);
DISPLAY INVISIBLE (-1050 -2100);
FORCEADD Q_RES..2
(-1125 -1800);
FORCEPROP 1 LAST PART_NUMBER CS35492FB03
J 0
(-1085 -1925);
DISPLAY 0.787234 (-1085 -1925);
DISPLAY INVISIBLE (-1085 -1925);
FORCEPROP 1 LAST TOLERANCE 1%
J 0
(-1080 -1775);
DISPLAY 0.787234 (-1080 -1775);
FORCEPROP 1 LAST MATERIAL EMPTY
J 0
(-1085 -1875);
DISPLAY 0.787234 (-1085 -1875);
PAINT RED (-1085 -1875);
FORCEPROP 1 LAST WATTAGE 1/16W
J 0
(-1085 -1825);
DISPLAY 0.787234 (-1085 -1825);
FORCEPROP 1 LAST VALUE 54.9K
J 0
(-1080 -1725);
DISPLAY 0.787234 (-1080 -1725);
FORCEPROP 1 LAST PACK_TYPE 0402LF
J 0
(-1085 -1975);
DISPLAY 0.787234 (-1085 -1975);
FORCEPROP 1 LAST $LOCATION R4551
J 0
(-1080 -1675);
DISPLAY 0.978723 (-1080 -1675);
FORCEPROP 1 LASTPIN (-1125 -1700) $PN 1
J 0
(-1120 -1738);
DISPLAY 0.787234 (-1120 -1738);
PAINT MONO (-1120 -1738);
FORCEPROP 1 LASTPIN (-1125 -1900) $PN 2
J 0
(-1120 -1890);
DISPLAY 0.787234 (-1120 -1890);
PAINT MONO (-1120 -1890);
FORCEPROP 1 LAST PATH I51
J 0
(-1075 -1625);
DISPLAY 0.978723 (-1075 -1625);
PAINT WHITE (-1075 -1625);
DISPLAY INVISIBLE (-1075 -1625);
FORCEPROP 2 LAST CDS_LIB pure_quanta
J 0
(-1125 -1800);
DISPLAY INVISIBLE (-1125 -1800);
FORCEPROP 0 LAST CDS_LOCATION R4551
J 0
(-1075 -1625);
DISPLAY 1.021277 (-1075 -1625);
DISPLAY INVISIBLE (-1075 -1625);
FORCEPROP 0 LAST $SEC 1
J 0
(-1075 -1625);
DISPLAY 0.680851 (-1075 -1625);
PAINT MONO (-1075 -1625);
DISPLAY INVISIBLE (-1075 -1625);
FORCEPROP 0 LAST CDS_SEC 1
J 0
(-1075 -1625);
DISPLAY 1.021277 (-1075 -1625);
DISPLAY INVISIBLE (-1075 -1625);
FORCEADD UNIVERSAL_POWER..1
(-1125 -1550);
FORCEPROP 3 LASTPIN (-1125 -1600) SIG_NAME P3V3_AUX\g
J 0
(-1115 -1590);
DISPLAY 0.659574 (-1115 -1590);
PAINT MONO (-1115 -1590);
DISPLAY INVISIBLE (-1115 -1590);
FORCEPROP 1 LAST HDL_POWER P3V3_AUX
J 1
(-1125 -1500);
DISPLAY 0.872340 (-1125 -1500);
PAINT GREEN (-1125 -1500);
FORCEPROP 1 LAST PATH I52
J 0
(-1075 -1525);
DISPLAY 0.872340 (-1075 -1525);
PAINT AQUA (-1075 -1525);
DISPLAY INVISIBLE (-1075 -1525);
FORCEPROP 2 LAST CDS_LIB logical_power
J 0
(-1125 -1550);
PAINT MONO (-1125 -1550);
DISPLAY INVISIBLE (-1125 -1550);
FORCEADD MOSFET_NCH_DUAL..1
(0 -2025);
FORCEPROP 1 LAST PART_NUMBER BAM138K0003
J 0
(151 -2111);
DISPLAY 0.723404 (151 -2111);
PAINT GREEN (151 -2111);
DISPLAY INVISIBLE (151 -2111);
FORCEPROP 2 LAST PART_TYPE SMLF
J 0
(175 -1950);
DISPLAY 1.021277 (175 -1950);
FORCEPROP 2 LAST VALUE PJT138K
J 0
(175 -2000);
DISPLAY 1.021277 (175 -2000);
FORCEPROP 1 LAST MATERIAL IC
J 0
(151 -2176);
DISPLAY 0.723404 (151 -2176);
PAINT GREEN (151 -2176);
FORCEPROP 1 LAST $LOCATION Q145
J 0
(151 -2051);
DISPLAY 0.723404 (151 -2051);
PAINT GREEN (151 -2051);
FORCEPROP 0 LASTPIN (50 -1825) $PN 6
R 1
J 0
(40 -1815);
DISPLAY 0.680851 (40 -1815);
PAINT MONO (40 -1815);
FORCEPROP 0 LASTPIN (-200 -2075) $PN 2
J 2
(-210 -2065);
DISPLAY 0.680851 (-210 -2065);
PAINT MONO (-210 -2065);
FORCEPROP 0 LASTPIN (50 -2225) $PN 1
R 1
J 2
(40 -2235);
DISPLAY 0.680851 (40 -2235);
PAINT MONO (40 -2235);
FORCEPROP 1 LAST PATH I53
J 0
(0 -2025);
DISPLAY 0.723404 (0 -2025);
PAINT GREEN (0 -2025);
DISPLAY INVISIBLE (0 -2025);
FORCEPROP 2 LAST CDS_LIB pure_quanta
J 0
(0 -2025);
DISPLAY INVISIBLE (0 -2025);
FORCEPROP 1 LAST NEEDS_NO_SIZE TRUE
J 0
(0 -2026);
DISPLAY 0.468085 (0 -2026);
PAINT GREEN (0 -2026);
DISPLAY INVISIBLE (0 -2026);
FORCEPROP 1 LAST CDS_LMAN_SYM_OUTLINE -150,150,150,-150
J 0
(0 -2025);
DISPLAY 0.468085 (0 -2025);
PAINT GREEN (0 -2025);
DISPLAY INVISIBLE (0 -2025);
FORCEPROP 2 LAST CDS_LOCATION Q145
J 0
(175 -1900);
DISPLAY 1.021277 (175 -1900);
DISPLAY INVISIBLE (175 -1900);
FORCEPROP 0 LAST $SEC 1
J 0
(175 -1900);
DISPLAY 0.680851 (175 -1900);
PAINT MONO (175 -1900);
DISPLAY INVISIBLE (175 -1900);
FORCEPROP 2 LAST CDS_SEC 1
J 0
(175 -1900);
DISPLAY 1.021277 (175 -1900);
DISPLAY INVISIBLE (175 -1900);
FORCEADD UNIVERSAL_GND..1
(50 -2400);
FORCEPROP 3 LASTPIN (50 -2350) SIG_NAME GND\g
J 0
(60 -2340);
DISPLAY 0.659574 (60 -2340);
PAINT MONO (60 -2340);
DISPLAY INVISIBLE (60 -2340);
FORCEPROP 1 LAST PATH I54
J 0
(125 -2400);
DISPLAY 0.872340 (125 -2400);
PAINT AQUA (125 -2400);
DISPLAY INVISIBLE (125 -2400);
FORCEPROP 2 LAST CDS_LIB logical_power
J 0
(50 -2400);
DISPLAY INVISIBLE (50 -2400);
FORCEPROP 1 LAST HDL_POWER GND
J 1
(75 -2475);
DISPLAY 0.872340 (75 -2475);
PAINT GREEN (75 -2475);
DISPLAY INVISIBLE (75 -2475);
FORCEADD Q_RES..2
(50 -1425);
FORCEPROP 1 LAST PART_NUMBER CS24702JB10
J 0
(90 -1600);
DISPLAY 0.638298 (90 -1600);
DISPLAY INVISIBLE (90 -1600);
FORCEPROP 1 LAST PACK_TYPE 0402LF
J 0
(90 -1550);
DISPLAY 0.638298 (90 -1550);
FORCEPROP 1 LAST MATERIAL CHIP
J 0
(90 -1500);
DISPLAY 0.638298 (90 -1500);
FORCEPROP 1 LAST WATTAGE 1/16W
J 0
(90 -1450);
DISPLAY 0.638298 (90 -1450);
FORCEPROP 1 LAST TOLERANCE 5%
J 0
(95 -1400);
DISPLAY 0.638298 (95 -1400);
FORCEPROP 1 LAST VALUE 4.7K
J 0
(95 -1350);
DISPLAY 0.638298 (95 -1350);
FORCEPROP 1 LAST $LOCATION R4553
J 0
(95 -1300);
DISPLAY 0.638298 (95 -1300);
FORCEPROP 1 LASTPIN (50 -1325) $PN 1
J 0
(55 -1363);
DISPLAY 0.787234 (55 -1363);
FORCEPROP 1 LASTPIN (50 -1525) $PN 2
J 0
(55 -1515);
DISPLAY 0.787234 (55 -1515);
FORCEPROP 1 LAST PATH I55
J 0
(100 -1250);
DISPLAY 0.978723 (100 -1250);
PAINT WHITE (100 -1250);
DISPLAY INVISIBLE (100 -1250);
FORCEPROP 2 LAST CDS_LIB pure_quanta
J 0
(50 -1425);
PAINT MONO (50 -1425);
DISPLAY INVISIBLE (50 -1425);
FORCEPROP 2 LAST CDS_LOCATION R4553
J 0
(100 -1200);
DISPLAY 1.021277 (100 -1200);
DISPLAY INVISIBLE (100 -1200);
FORCEPROP 2 LAST $SEC 1
J 0
(100 -1200);
DISPLAY 0.680851 (100 -1200);
PAINT MONO (100 -1200);
DISPLAY INVISIBLE (100 -1200);
FORCEPROP 2 LAST CDS_SEC 1
J 0
(100 -1200);
DISPLAY 1.021277 (100 -1200);
DISPLAY INVISIBLE (100 -1200);
FORCEADD UNIVERSAL_POWER..1
(50 -1200);
FORCEPROP 3 LASTPIN (50 -1250) SIG_NAME P3V3_AUX\g
J 0
(60 -1240);
DISPLAY 0.659574 (60 -1240);
PAINT MONO (60 -1240);
DISPLAY INVISIBLE (60 -1240);
FORCEPROP 1 LAST HDL_POWER P3V3_AUX
J 1
(50 -1150);
DISPLAY 0.872340 (50 -1150);
PAINT GREEN (50 -1150);
FORCEPROP 1 LAST PATH I56
J 0
(100 -1175);
DISPLAY 0.872340 (100 -1175);
PAINT AQUA (100 -1175);
DISPLAY INVISIBLE (100 -1175);
FORCEPROP 2 LAST CDS_LIB logical_power
J 0
(50 -1200);
PAINT MONO (50 -1200);
DISPLAY INVISIBLE (50 -1200);
FORCEADD UNIVERSAL_GND..1
(1200 -2100);
FORCEPROP 3 LASTPIN (1200 -2050) SIG_NAME GND\g
J 0
(1210 -2040);
DISPLAY 0.659574 (1210 -2040);
PAINT MONO (1210 -2040);
DISPLAY INVISIBLE (1210 -2040);
FORCEPROP 1 LAST PATH I57
J 0
(1275 -2100);
DISPLAY 0.872340 (1275 -2100);
PAINT AQUA (1275 -2100);
DISPLAY INVISIBLE (1275 -2100);
FORCEPROP 2 LAST CDS_LIB logical_power
J 0
(1200 -2100);
DISPLAY INVISIBLE (1200 -2100);
FORCEPROP 1 LAST HDL_POWER GND
J 1
(1225 -2175);
DISPLAY 0.872340 (1225 -2175);
PAINT GREEN (1225 -2175);
DISPLAY INVISIBLE (1225 -2175);
FORCEADD MOSFET_NCH_DUAL..2
(1150 -1725);
FORCEPROP 1 LAST PART_NUMBER BAM138K0003
J 0
(1301 -1819);
DISPLAY 0.723404 (1301 -1819);
PAINT GREEN (1301 -1819);
DISPLAY INVISIBLE (1301 -1819);
FORCEPROP 1 LAST MATERIAL IC
J 0
(1301 -1874);
DISPLAY 0.723404 (1301 -1874);
PAINT GREEN (1301 -1874);
FORCEPROP 2 LAST VALUE PJT138K
J 0
(1325 -1700);
DISPLAY 1.021277 (1325 -1700);
FORCEPROP 2 LAST PART_TYPE SMLF
J 0
(1325 -1650);
DISPLAY 1.021277 (1325 -1650);
FORCEPROP 1 LAST $LOCATION Q145
J 0
(1301 -1749);
DISPLAY 0.723404 (1301 -1749);
PAINT GREEN (1301 -1749);
FORCEPROP 0 LASTPIN (1200 -1525) $PN 3
R 1
J 0
(1190 -1515);
DISPLAY 0.680851 (1190 -1515);
PAINT MONO (1190 -1515);
FORCEPROP 0 LASTPIN (950 -1775) $PN 5
J 2
(940 -1765);
DISPLAY 0.680851 (940 -1765);
PAINT MONO (940 -1765);
FORCEPROP 0 LASTPIN (1200 -1925) $PN 4
R 1
J 2
(1190 -1935);
DISPLAY 0.680851 (1190 -1935);
PAINT MONO (1190 -1935);
FORCEPROP 1 LAST PATH I58
J 0
(1300 -1875);
DISPLAY 0.723404 (1300 -1875);
PAINT GREEN (1300 -1875);
DISPLAY INVISIBLE (1300 -1875);
FORCEPROP 1 LAST CDS_LMAN_SYM_OUTLINE -150,150,150,-150
J 0
(1150 -1725);
DISPLAY 0.468085 (1150 -1725);
PAINT GREEN (1150 -1725);
DISPLAY INVISIBLE (1150 -1725);
FORCEPROP 1 LAST NEEDS_NO_SIZE TRUE
J 0
(1300 -1834);
DISPLAY 0.468085 (1300 -1834);
PAINT GREEN (1300 -1834);
DISPLAY INVISIBLE (1300 -1834);
FORCEPROP 2 LAST CDS_LIB pure_quanta
J 0
(1150 -1725);
DISPLAY INVISIBLE (1150 -1725);
FORCEPROP 0 LAST CDS_LOCATION Q145
J 0
(1325 -1600);
DISPLAY 1.021277 (1325 -1600);
DISPLAY INVISIBLE (1325 -1600);
FORCEPROP 0 LAST $SEC 2
J 0
(1325 -1600);
DISPLAY 0.680851 (1325 -1600);
PAINT MONO (1325 -1600);
DISPLAY INVISIBLE (1325 -1600);
FORCEPROP 0 LAST CDS_SEC 2
J 0
(1325 -1600);
DISPLAY 1.021277 (1325 -1600);
DISPLAY INVISIBLE (1325 -1600);
FORCEADD Q_RES..2
(1200 -1300);
FORCEPROP 1 LAST PART_NUMBER CS24702JB10
J 0
(1240 -1475);
DISPLAY 0.638298 (1240 -1475);
DISPLAY INVISIBLE (1240 -1475);
FORCEPROP 1 LAST MATERIAL CHIP
J 0
(1240 -1375);
DISPLAY 0.638298 (1240 -1375);
FORCEPROP 1 LAST TOLERANCE 5%
J 0
(1245 -1275);
DISPLAY 0.638298 (1245 -1275);
FORCEPROP 1 LAST WATTAGE 1/16W
J 0
(1240 -1325);
DISPLAY 0.638298 (1240 -1325);
FORCEPROP 1 LAST VALUE 4.7K
J 0
(1245 -1225);
DISPLAY 0.638298 (1245 -1225);
FORCEPROP 1 LAST PACK_TYPE 0402LF
J 0
(1240 -1425);
DISPLAY 0.638298 (1240 -1425);
FORCEPROP 1 LAST $LOCATION R4554
J 0
(1245 -1175);
DISPLAY 0.638298 (1245 -1175);
FORCEPROP 1 LASTPIN (1200 -1200) $PN 1
J 0
(1205 -1238);
DISPLAY 0.787234 (1205 -1238);
FORCEPROP 1 LASTPIN (1200 -1400) $PN 2
J 0
(1205 -1390);
DISPLAY 0.787234 (1205 -1390);
FORCEPROP 1 LAST PATH I59
J 0
(1250 -1125);
DISPLAY 0.978723 (1250 -1125);
PAINT WHITE (1250 -1125);
DISPLAY INVISIBLE (1250 -1125);
FORCEPROP 2 LAST CDS_LIB pure_quanta
J 0
(1200 -1300);
PAINT MONO (1200 -1300);
DISPLAY INVISIBLE (1200 -1300);
FORCEPROP 2 LAST CDS_LOCATION R4554
J 0
(1250 -1075);
DISPLAY 1.021277 (1250 -1075);
DISPLAY INVISIBLE (1250 -1075);
FORCEPROP 2 LAST $SEC 1
J 0
(1250 -1075);
DISPLAY 0.680851 (1250 -1075);
PAINT MONO (1250 -1075);
DISPLAY INVISIBLE (1250 -1075);
FORCEPROP 2 LAST CDS_SEC 1
J 0
(1250 -1075);
DISPLAY 1.021277 (1250 -1075);
DISPLAY INVISIBLE (1250 -1075);
FORCEADD UNIVERSAL_GND..1
(-1775 2425);
FORCEPROP 3 LASTPIN (-1775 2475) SIG_NAME GND\g
J 0
(-1765 2485);
DISPLAY 0.659574 (-1765 2485);
PAINT MONO (-1765 2485);
DISPLAY INVISIBLE (-1765 2485);
FORCEPROP 1 LAST PATH I6
J 0
(-1700 2425);
DISPLAY 0.872340 (-1700 2425);
PAINT AQUA (-1700 2425);
DISPLAY INVISIBLE (-1700 2425);
FORCEPROP 1 LAST HDL_POWER GND
J 1
(-1750 2350);
DISPLAY 0.872340 (-1750 2350);
PAINT GREEN (-1750 2350);
DISPLAY INVISIBLE (-1750 2350);
FORCEPROP 2 LAST CDS_LIB logical_power
J 0
(-1775 2425);
DISPLAY INVISIBLE (-1775 2425);
FORCEADD UNIVERSAL_POWER..1
(1200 -1075);
FORCEPROP 3 LASTPIN (1200 -1125) SIG_NAME P3V3_AUX\g
J 0
(1210 -1115);
DISPLAY 0.659574 (1210 -1115);
PAINT MONO (1210 -1115);
DISPLAY INVISIBLE (1210 -1115);
FORCEPROP 1 LAST HDL_POWER P3V3_AUX
J 1
(1200 -1025);
DISPLAY 0.872340 (1200 -1025);
PAINT GREEN (1200 -1025);
FORCEPROP 1 LAST PATH I60
J 0
(1250 -1050);
DISPLAY 0.872340 (1250 -1050);
PAINT AQUA (1250 -1050);
DISPLAY INVISIBLE (1250 -1050);
FORCEPROP 2 LAST CDS_LIB logical_power
J 0
(1200 -1075);
PAINT MONO (1200 -1075);
DISPLAY INVISIBLE (1200 -1075);
FORCEADD UNIVERSAL_GND..1
(1975 -1975);
FORCEPROP 3 LASTPIN (1975 -1925) SIG_NAME GND\g
J 0
(1985 -1915);
DISPLAY 0.659574 (1985 -1915);
PAINT MONO (1985 -1915);
DISPLAY INVISIBLE (1985 -1915);
FORCEPROP 1 LAST PATH I61
J 0
(2050 -1975);
DISPLAY 0.872340 (2050 -1975);
PAINT AQUA (2050 -1975);
DISPLAY INVISIBLE (2050 -1975);
FORCEPROP 2 LAST CDS_LIB logical_power
J 0
(1975 -1975);
DISPLAY INVISIBLE (1975 -1975);
FORCEPROP 1 LAST HDL_POWER GND
J 1
(2000 -2050);
DISPLAY 0.872340 (2000 -2050);
PAINT GREEN (2000 -2050);
DISPLAY INVISIBLE (2000 -2050);
FORCEADD Q_CAP..1
(1975 -1775);
FORCEPROP 1 LAST PART_NUMBER TMP_QCH21006JB10
J 0
(2025 -1925);
DISPLAY 0.638298 (2025 -1925);
DISPLAY INVISIBLE (2025 -1925);
FORCEPROP 1 LAST VOLTAGE 50V
J 0
(2025 -1775);
DISPLAY 0.638298 (2025 -1775);
FORCEPROP 1 LAST PACK_TYPE 0402
J 0
(2025 -1975);
DISPLAY 0.638298 (2025 -1975);
FORCEPROP 1 LAST TOLERANCE 5%
J 0
(2025 -1825);
DISPLAY 0.638298 (2025 -1825);
FORCEPROP 1 LAST MATERIAL EMPTY
J 0
(2025 -1875);
DISPLAY 0.638298 (2025 -1875);
PAINT RED (2025 -1875);
FORCEPROP 1 LAST VALUE 1000PF
J 0
(2025 -1725);
DISPLAY 0.638298 (2025 -1725);
FORCEPROP 1 LAST $LOCATION C2342
J 0
(2025 -1675);
DISPLAY 0.978723 (2025 -1675);
FORCEPROP 1 LASTPIN (1975 -1675) $PN 1
J 0
(1985 -1695);
DISPLAY 0.787234 (1985 -1695);
PAINT MONO (1985 -1695);
FORCEPROP 1 LASTPIN (1975 -1875) $PN 2
J 0
(1985 -1895);
DISPLAY 0.787234 (1985 -1895);
PAINT MONO (1985 -1895);
FORCEPROP 1 LAST PATH I62
J 0
(2025 -1625);
DISPLAY 0.978723 (2025 -1625);
PAINT WHITE (2025 -1625);
DISPLAY INVISIBLE (2025 -1625);
FORCEPROP 2 LAST CDS_LIB pure_quanta
J 0
(1975 -1775);
DISPLAY INVISIBLE (1975 -1775);
FORCEPROP 0 LAST CDS_LOCATION C2342
J 0
(2025 -1625);
DISPLAY 1.021277 (2025 -1625);
DISPLAY INVISIBLE (2025 -1625);
FORCEPROP 0 LAST $SEC 1
J 0
(2025 -1625);
DISPLAY 0.680851 (2025 -1625);
PAINT MONO (2025 -1625);
DISPLAY INVISIBLE (2025 -1625);
FORCEPROP 0 LAST CDS_SEC 1
J 0
(2025 -1625);
DISPLAY 1.021277 (2025 -1625);
DISPLAY INVISIBLE (2025 -1625);
FORCEADD OFFPAGE..2
(2325 -1475);
FORCEPROP 2 LAST $XR0 215 
J 0
(2514 -1475);
DISPLAY 0.638298 (2514 -1475);
PAINT MONO (2514 -1475);
FORCEPROP 2 LAST PATH I63
J 0
(2525 -1425);
DISPLAY 1.021277 (2525 -1425);
DISPLAY INVISIBLE (2525 -1425);
FORCEPROP 2 LAST CDS_LIB standard
J 0
(2325 -1475);
DISPLAY INVISIBLE (2325 -1475);
FORCEPROP 1 LAST COMMENT_BODY TRUE
J 0
(2280 -1570);
DISPLAY 0.872340 (2280 -1570);
PAINT GREEN (2280 -1570);
DISPLAY INVISIBLE (2280 -1570);
FORCEPROP 1 LAST OFFPAGE TRUE
J 0
(2650 -1600);
DISPLAY 0.872340 (2650 -1600);
PAINT AQUA (2650 -1600);
DISPLAY INVISIBLE (2650 -1600);
FORCEADD UNIVERSAL_GND..1
(-1100 -2550);
FORCEPROP 3 LASTPIN (-1100 -2500) SIG_NAME GND\g
J 0
(-1090 -2490);
DISPLAY 0.659574 (-1090 -2490);
PAINT MONO (-1090 -2490);
DISPLAY INVISIBLE (-1090 -2490);
FORCEPROP 1 LAST PATH I64
J 0
(-1025 -2550);
DISPLAY 0.872340 (-1025 -2550);
PAINT AQUA (-1025 -2550);
DISPLAY INVISIBLE (-1025 -2550);
FORCEPROP 2 LAST CDS_LIB logical_power
J 0
(-1100 -2550);
DISPLAY INVISIBLE (-1100 -2550);
FORCEPROP 1 LAST HDL_POWER GND
J 1
(-1075 -2625);
DISPLAY 0.872340 (-1075 -2625);
PAINT GREEN (-1075 -2625);
DISPLAY INVISIBLE (-1075 -2625);
FORCEADD OFFPAGE..4
R 2
(-2025 2825);
FORCEPROP 2 LAST $XR0 213 
J 0
(-2277 2825);
DISPLAY 0.638298 (-2277 2825);
PAINT MONO (-2277 2825);
FORCEPROP 2 LAST PATH I7
J 0
(-2300 2875);
DISPLAY 1.021277 (-2300 2875);
DISPLAY INVISIBLE (-2300 2875);
FORCEPROP 1 LAST OFFPAGE TRUE
J 2
(-2350 2700);
DISPLAY 0.872340 (-2350 2700);
PAINT GREEN (-2350 2700);
DISPLAY INVISIBLE (-2350 2700);
FORCEPROP 1 LAST COMMENT_BODY TRUE
J 2
(-2000 2725);
DISPLAY 0.872340 (-2000 2725);
PAINT GREEN (-2000 2725);
DISPLAY INVISIBLE (-2000 2725);
FORCEPROP 2 LAST CDS_LIB standard
J 0
(-2025 2825);
DISPLAY INVISIBLE (-2025 2825);
FORCEADD QUANTA_TITLE_BLOCK_C..1
(4975 -2975);
FORCEPROP 0 LAST CDS_CON_LAST_MODIFIED Fri Aug 25 14:04:16 2023
J 0
(3090 -2960);
DISPLAY INVISIBLE (3090 -2960);
FORCEPROP 1 LAST CUSTOM_TXT_CDS <CON_LAST_MODIFIED>
J 0
(3090 -2960);
DISPLAY 0.978723 (3090 -2960);
FORCEPROP 2 LAST CUSTOM_TXT_CDS <XR_PAGE_TITLE>
J 0
(-2915 2275);
DISPLAY 0.638298 (-2915 2275);
PAINT PINK (-2915 2275);
DISPLAY INVISIBLE (-2915 2275);
FORCEPROP 1 LAST CUSTOM_TXT_CDS <NAME_2>
J 0
(1800 -2925);
FORCEPROP 1 LAST CUSTOM_TXT_CDS <NAME_1>
J 0
(1800 -2800);
FORCEPROP 1 LAST CUSTOM_TXT_CDS <Q_NUMBER>
J 0
(3572 -2872);
DISPLAY 1.212766 (3572 -2872);
FORCEPROP 1 LAST CUSTOM_TXT_CDS <Q_PROJ>
J 0
(2593 -2873);
DISPLAY 1.212766 (2593 -2873);
FORCEPROP 1 LAST CUSTOM_TXT_CDS <Q_REV>
J 0
(4791 -2872);
DISPLAY 1.212766 (4791 -2872);
FORCEPROP 1 LAST CUSTOM_TXT_CDS <CON_PAGE_NUM> OF <CON_TOTAL_PAGES>
J 0
(4529 -2957);
DISPLAY 0.978723 (4529 -2957);
FORCEPROP 1 LAST Q_TITLE POWER CONNECTOR/ISOLATED
J 0
(-4391 -2949);
DISPLAY 2.446809 (-4391 -2949);
PAINT GREEN (-4391 -2949);
FORCEPROP 1 LAST Q_DEPT 
J 1
(1212 -2926);
DISPLAY 1.957447 (1212 -2926);
PAINT GREEN (1212 -2926);
FORCEPROP 2 LAST CDS_XR_PAGE_TITLE CR-246 : @S9S_MB_2U_LIB.S9S_MB_2U(SCH_1):PAGE246
J 0
(-2915 2275);
DISPLAY 0.638298 (-2915 2275);
PAINT PINK (-2915 2275);
DISPLAY INVISIBLE (-2915 2275);
FORCEPROP 2 LAST PAGE_BORDER TRUE
J 0
(-2915 2275);
DISPLAY 0.638298 (-2915 2275);
PAINT PINK (-2915 2275);
DISPLAY INVISIBLE (-2915 2275);
FORCEPROP 1 LAST COMMENT_BODY TRUE
J 0
(4987 -2988);
DISPLAY 0.978723 (4987 -2988);
PAINT GREEN (4987 -2988);
DISPLAY INVISIBLE (4987 -2988);
FORCEPROP 1 LAST CDS_LMAN_SYM_OUTLINE -9475,6775,100,-125
J 0
(4975 -2975);
DISPLAY 0.468085 (4975 -2975);
PAINT GREEN (4975 -2975);
DISPLAY INVISIBLE (4975 -2975);
FORCEPROP 2 LAST CDS_LIB pure_quanta
J 0
(4975 -2975);
DISPLAY INVISIBLE (4975 -2975);
FORCEADD DNS..2
(-1800 3075);
PAINT RED (-1800 3075);
FORCEPROP 1 LAST COMMENT_BODY TRUE
J 0
(-1800 3075);
DISPLAY INVISIBLE (-1800 3075);
FORCEPROP 2 LAST CDS_LIB mstr_misc
J 0
(-1800 3075);
DISPLAY INVISIBLE (-1800 3075);
FORCEADD DNS..2
(1725 2300);
PAINT RED (1725 2300);
FORCEPROP 1 LAST COMMENT_BODY TRUE
J 0
(1725 2300);
DISPLAY INVISIBLE (1725 2300);
FORCEPROP 2 LAST CDS_LIB mstr_misc
J 0
(1725 2300);
DISPLAY INVISIBLE (1725 2300);
FORCEADD DNS..2
(1750 1750);
PAINT RED (1750 1750);
FORCEPROP 2 LAST CDS_LIB mstr_misc
J 0
(1750 1750);
DISPLAY INVISIBLE (1750 1750);
FORCEPROP 1 LAST COMMENT_BODY TRUE
J 0
(1750 1750);
DISPLAY INVISIBLE (1750 1750);
FORCEADD DNS..2
(2175 -50);
PAINT RED (2175 -50);
FORCEPROP 1 LAST COMMENT_BODY TRUE
J 0
(2175 -50);
DISPLAY INVISIBLE (2175 -50);
FORCEPROP 2 LAST CDS_LIB mstr_misc
J 0
(2175 -50);
DISPLAY INVISIBLE (2175 -50);
FORCEADD DNS..2
(1975 -1800);
PAINT RED (1975 -1800);
FORCEPROP 2 LAST CDS_LIB mstr_misc
J 0
(1975 -1800);
DISPLAY INVISIBLE (1975 -1800);
FORCEPROP 1 LAST COMMENT_BODY TRUE
J 0
(1975 -1800);
DISPLAY INVISIBLE (1975 -1800);
FORCEADD DNS..2
(-1125 -1825);
PAINT RED (-1125 -1825);
FORCEPROP 1 LAST COMMENT_BODY TRUE
J 0
(-1125 -1825);
DISPLAY INVISIBLE (-1125 -1825);
FORCEPROP 2 LAST CDS_LIB mstr_misc
J 0
(-1125 -1825);
DISPLAY INVISIBLE (-1125 -1825);
WIRE 16 -1 (-1125 -1600)(-1125 -1700);
WIRE 16 -1 (50 -1250)(50 -1325);
WIRE 16 -1 (1200 -1125)(1200 -1200);
WIRE 16 -1 (-1800 3300)(-1800 3200);
WIRE 16 -1 (1725 2525)(1725 2425);
WIRE 16 -1 (1250 -75)(1250 -175);
WIRE 16 -1 (2150 725)(2150 625);
WIRE 16 -1 (925 2750)(925 2675);
WIRE 16 -1 (1750 1675)(1750 1600);
WIRE 16 -1 (925 2375)(925 2300);
WIRE 16 -1 (2175 -125)(2175 -200);
WIRE 16 -1 (1250 -450)(1250 -525);
WIRE 16 -1 (-150 2025)(-150 1900);
WIRE 16 -1 (-150 2025)(-50 2025);
WIRE 16 -1 (-1775 2475)(-1775 2525);
WIRE 16 -1 (-25 225)(-25 125);
WIRE 16 -1 (225 225)(-25 225);
WIRE 16 -1 (-1100 -2375)(-1100 -2500);
WIRE 16 -1 (1975 -1875)(1975 -1925);
WIRE 16 -1 (1200 -1925)(1200 -2050);
WIRE 16 -1 (50 -2225)(50 -2350);
WIRE 16 -1 (-1100 -2175)(-1100 -2075);
WIRE 16 -1 (-200 -2075)(-1100 -2075);
FORCEPROP 2 LAST SIG_NAME HPDB_HSC_PWRGD
J 0
(-1060 -2065);
DISPLAY 0.808511 (-1060 -2065);
WIRE 16 -1 (-1125 -2075)(-1325 -2075);
WIRE 16 -1 (-1100 -2075)(-1125 -2075);
WIRE 16 -1 (-1125 -1900)(-1125 -2075);
WIRE 16 2175 (-2550 1350)(4050 1350);
WIRE 16 2175 (4050 1350)(4050 -725);
WIRE 16 2175 (-2550 1350)(-2550 -725);
WIRE 16 2175 (-2550 -725)(4050 -725);
WIRE 16 -1 (-2125 275)(-1225 275);
FORCEPROP 2 LAST SIG_NAME PWRGD_P3V3_AUX_PDB
J 0
(-2060 285);
DISPLAY 0.851064 (-2060 285);
PAINT WHITE (-2060 285);
WIRE 16 -1 (50 -1825)(50 -1775);
WIRE 16 -1 (950 -1775)(50 -1775);
FORCEPROP 2 LAST SIG_NAME HPDB_HSC_PWRGD_N
J 0
(65 -1765);
DISPLAY 1.021277 (65 -1765);
WIRE 16 -1 (50 -1525)(50 -1775);
WIRE 16 -1 (1200 -1475)(1200 -1525);
WIRE 16 -1 (1200 -1400)(1200 -1475);
WIRE 16 -1 (1975 -1475)(1200 -1475);
FORCEPROP 2 LAST SIG_NAME HPDB_HSC_PWRGD_ISO
J 0
(1265 -1465);
DISPLAY 0.808511 (1265 -1465);
WIRE 16 -1 (1975 -1675)(1975 -1475);
WIRE 16 -1 (2275 -1475)(1975 -1475);
WIRE 16 -1 (3625 275)(2500 275);
FORCEPROP 2 LAST SIG_NAME PWRGD_P3V3_AUX_PDB_BUF
J 0
(2690 285);
DISPLAY 0.808511 (2690 285);
PAINT WHITE (2690 285);
WIRE 16 -1 (-1800 2825)(-1975 2825);
WIRE 16 -1 (-1800 3000)(-1800 2825);
WIRE 16 -1 (-1800 2825)(-1775 2825);
WIRE 16 -1 (-1775 2725)(-1775 2825);
WIRE 16 -1 (-450 2825)(-1775 2825);
FORCEPROP 2 LAST SIG_NAME FM_GPU_HSC_EN
J 0
(-1510 2835);
DISPLAY 0.808511 (-1510 2835);
PAINT WHITE (-1510 2835);
WIRE 16 -1 (-450 2825)(-450 2225);
WIRE 16 -1 (-450 2225)(-50 2225);
WIRE 16 -1 (-1975 2125)(-1425 2125);
FORCEPROP 2 LAST SIG_NAME GPU_PRSNT
J 0
(-1935 2135);
DISPLAY 0.808511 (-1935 2135);
PAINT WHITE (-1935 2135);
WIRE 16 -1 (1750 1875)(1750 2075);
WIRE 16 -1 (1750 2075)(1900 2075);
WIRE 16 -1 (1725 2075)(550 2075);
FORCEPROP 2 LAST SIG_NAME FM_GPU_HSC_EN_BUF_R
J 0
(1015 2085);
DISPLAY 0.638298 (1015 2085);
PAINT WHITE (1015 2085);
WIRE 16 -1 (1725 2075)(1750 2075);
WIRE 16 -1 (1725 2225)(1725 2075);
WIRE 16 -1 (925 2675)(925 2575);
WIRE 16 -1 (925 2675)(800 2675);
WIRE 16 -1 (800 2225)(800 2675);
WIRE 16 -1 (550 2225)(800 2225);
WIRE 16 -1 (-1225 2125)(-50 2125);
FORCEPROP 2 LAST SIG_NAME GPU_PRSNT_R
J 0
(-760 2135);
DISPLAY 0.808511 (-760 2135);
PAINT WHITE (-760 2135);
WIRE 16 -1 (1250 -175)(1250 -250);
WIRE 16 -1 (1075 -175)(1250 -175);
WIRE 16 -1 (1075 225)(1075 -175);
WIRE 16 -1 (875 225)(1075 225);
WIRE 16 -1 (2175 75)(2175 275);
WIRE 16 -1 (2175 275)(2300 275);
WIRE 16 -1 (2150 275)(875 275);
FORCEPROP 2 LAST SIG_NAME PWRGD_P3V3_AUX_PDB_BUF_R
J 0
(1065 285);
DISPLAY 0.851064 (1065 285);
PAINT WHITE (1065 285);
WIRE 16 -1 (2175 275)(2150 275);
WIRE 16 -1 (2150 425)(2150 275);
WIRE 16 -1 (-1025 275)(225 275);
FORCEPROP 2 LAST SIG_NAME PWRGD_P3V3_AUX_PDB_R
J 0
(-685 285);
DISPLAY 0.851064 (-685 285);
PAINT WHITE (-685 285);
WIRE 16 -1 (3225 2075)(2100 2075);
FORCEPROP 2 LAST SIG_NAME FM_GPU_HSC_EN_BUF
J 0
(2290 2085);
DISPLAY 0.808511 (2290 2085);
PAINT WHITE (2290 2085);
DOT 1 (-1100 -2075);
DOT 1 (1200 -1475);
DOT 1 (-1125 -2075);
DOT 1 (50 -1775);
DOT 1 (1725 2075);
DOT 1 (925 2675);
DOT 1 (1750 2075);
DOT 1 (2175 275);
DOT 1 (2150 275);
DOT 1 (1250 -175);
DOT 1 (1975 -1475);
DOT 1 (-1775 2825);
DOT 1 (-1800 2825);
FORCENOTE
20211201 ADD BUF TO PDB
(225 -825) 0;
DISPLAY LEFT (225 -825);
DISPLAY 1.063830 (225 -825);
PAINT WHITE (225 -825);
FORCENOTE
20210616 MODIFY FOR GT
(-650 3375) 0;
DISPLAY LEFT (-650 3375);
DISPLAY 2.510638 (-650 3375);
PAINT PINK (-650 3375);
FORCENOTE
OUT PUT IS PUSH PULL MODE
(-625 1625) 0;
DISPLAY LEFT (-625 1625);
DISPLAY 1.595745 (-625 1625);
PAINT PINK (-625 1625);
QUIT
